# BASEBOARD_FAB2 (Tioga Pass) — schematic netlist excerpt (pin names and nets, part order shuffled) for the footprints in the layout excerpt that follows; sources: Cadence DE-HDL packaged netlist, KiCad conversion of Wiwynn_Tioga_Pass_MB.brd

R7E13  RES  0.0 5% CHIP  pkg 0402  page 241 : A = GND ; B = AGND_P5V_STBY
R4D56  RES  0.0 5% CHIP  pkg 0402  page 213 : A = SVID_ALERT_PVCCIO_CPU1 ; B = SVID_ALERT0_CPU1_R_N

(kicad_pcb
	(version 20260206)
	(generator "pcbnew")
	(generator_version "10.0")
	(general
		(thickness 1.6)
		(legacy_teardrops no)
	)
	(paper "A4")
	(title_block
		(title "Wiwynn_Tioga_Pass_MB.brd")
		(comment 1 "Tioga Pass / footprints 1124-1125 of 4770")
	)
	(layers
		(0 "F.Cu" signal "TOP")
		(4 "In1.Cu" signal "L2GND")
		(6 "In2.Cu" signal "L3")
		(8 "In3.Cu" signal "L4GND")
		(10 "In4.Cu" signal "L5")
		(12 "In5.Cu" signal "L6GND")
		(14 "In6.Cu" signal "L7VCC")
		(16 "In7.Cu" signal "L8VCC")
		(18 "In8.Cu" signal "L9GND")
		(20 "In9.Cu" signal "L10")
		(22 "In10.Cu" signal "L11GND")
		(24 "In11.Cu" signal "L12")
		(26 "In12.Cu" signal "L13GND")
		(2 "B.Cu" signal "BOTTOM")
		(9 "F.Adhes" user "F.Adhesive")
		(11 "B.Adhes" user "B.Adhesive")
		(13 "F.Paste" user "Package Geometry/Pastemask Top")
		(15 "B.Paste" user "Package Geometry/Pastemask Bottom")
		(5 "F.SilkS" user "Ref Des/Silkscreen Top")
		(7 "B.SilkS" user "Ref Des/Silkscreen Bottom")
		(1 "F.Mask" user "Board Geometry/Soldermask Top")
		(3 "B.Mask" user "Board Geometry/Soldermask Bottom")
		(17 "Dwgs.User" user "User.Drawings")
		(19 "Cmts.User" user "User.Comments")
		(21 "Eco1.User" user "User.Eco1")
		(23 "Eco2.User" user "User.Eco2")
		(25 "Edge.Cuts" user "Board Geometry/Outline")
		(27 "Margin" user)
		(31 "F.CrtYd" user "Package Geometry/Place Bound Top")
		(29 "B.CrtYd" user "Package Geometry/Place Bound Bottom")
		(35 "F.Fab" user "Ref Des/Assembly Top")
		(33 "B.Fab" user "Ref Des/Assembly Bottom")
	)
	(footprint ""
		(layer "F.Cu")
		(at 389.636 -71.0565 180)
		(property "Reference" "R7E13"
			(at 0 0 180)
			(layer "F.SilkS")
			(hide yes)
			(effects
				(font
					(size 1.27 1.27)
				)
			)
		)
		(property "Value" ""
			(at 0 0 180)
			(layer "F.Fab")
			(effects
				(font
					(size 1.27 1.27)
				)
			)
		)
		(duplicate_pad_numbers_are_jumpers no)
		(fp_poly
			(pts
				(xy -0.2794 -0.1016) (xy 0.2794 -0.1016) (xy 0.2794 0.9906) (xy -0.2794 0.9906)
			)
			(stroke
				(width 0)
				(type default)
			)
			(fill no)
			(layer "F.CrtYd")
		)
		(fp_line
			(start 0.2794 0.9906)
			(end 0.2794 -0.1016)
			(stroke
				(width 0.1)
				(type default)
			)
			(layer "F.Fab")
		)
		(fp_line
			(start 0.2794 -0.1016)
			(end -0.2794 -0.1016)
			(stroke
				(width 0.1)
				(type default)
			)
			(layer "F.Fab")
		)
		(fp_line
			(start -0.2794 0.9906)
			(end 0.2794 0.9906)
			(stroke
				(width 0.1)
				(type default)
			)
			(layer "F.Fab")
		)
		(fp_line
			(start -0.2794 -0.1016)
			(end -0.2794 0.9906)
			(stroke
				(width 0.1)
				(type default)
			)
			(layer "F.Fab")
		)
		(pad "1" smd rect
			(at 0 0 180)
			(size 0.508 0.508)
			(layers "F.Cu" "F.Mask" "F.Paste")
			(net "GND")
		)
		(pad "2" smd rect
			(at 0 0.889 180)
			(size 0.508 0.508)
			(layers "F.Cu" "F.Mask" "F.Paste")
			(net "AGND_P5V_STBY")
		)
		(zone
			(layer "F.Cu")
			(hatch none 0.5)
			(connect_pads
				(clearance 0)
			)
			(min_thickness 0.25)
			(keepout
				(tracks not_allowed)
				(vias allowed)
				(pads allowed)
				(copperpour not_allowed)
				(footprints allowed)
			)
			(placement
				(enabled no)
				(sheetname "")
			)
			(fill
				(thermal_gap 0.5)
				(thermal_bridge_width 0.5)
				(island_removal_mode 0)
			)
			(polygon
				(pts
					(xy 389.89 -71.6915) (xy 389.382 -71.6915) (xy 389.382 -71.3105) (xy 389.89 -71.3105)
				)
			)
		)
		(zone
			(layer "F.Cu")
			(hatch none 0.5)
			(connect_pads
				(clearance 0)
			)
			(min_thickness 0.25)
			(keepout
				(tracks allowed)
				(vias not_allowed)
				(pads allowed)
				(copperpour not_allowed)
				(footprints allowed)
			)
			(placement
				(enabled no)
				(sheetname "")
			)
			(fill
				(thermal_gap 0.5)
				(thermal_bridge_width 0.5)
				(island_removal_mode 0)
			)
			(polygon
				(pts
					(xy 389.89 -71.3105) (xy 389.382 -71.3105) (xy 389.382 -71.6915) (xy 389.89 -71.6915)
				)
			)
		)
	)
	(footprint ""
		(layer "F.Cu")
		(at 164.973 -67.31 -90)
		(property "Reference" "R4D56"
			(at 0 0 270)
			(layer "F.SilkS")
			(hide yes)
			(effects
				(font
					(size 1.27 1.27)
				)
			)
		)
		(property "Value" ""
			(at 0 0 270)
			(layer "F.Fab")
			(effects
				(font
					(size 1.27 1.27)
				)
			)
		)
		(duplicate_pad_numbers_are_jumpers no)
		(fp_poly
			(pts
				(xy -0.2794 -0.1016) (xy 0.2794 -0.1016) (xy 0.2794 0.9906) (xy -0.2794 0.9906)
			)
			(stroke
				(width 0)
				(type default)
			)
			(fill no)
			(layer "F.CrtYd")
		)
		(fp_line
			(start -0.2794 0.9906)
			(end 0.2794 0.9906)
			(stroke
				(width 0.1)
				(type default)
			)
			(layer "F.Fab")
		)
		(fp_line
			(start 0.2794 0.9906)
			(end 0.2794 -0.1016)
			(stroke
				(width 0.1)
				(type default)
			)
			(layer "F.Fab")
		)
		(fp_line
			(start -0.2794 -0.1016)
			(end -0.2794 0.9906)
			(stroke
				(width 0.1)
				(type default)
			)
			(layer "F.Fab")
		)
		(fp_line
			(start 0.2794 -0.1016)
			(end -0.2794 -0.1016)
			(stroke
				(width 0.1)
				(type default)
			)
			(layer "F.Fab")
		)
		(pad "1" smd rect
			(at 0 0 270)
			(size 0.508 0.508)
			(layers "F.Cu" "F.Mask" "F.Paste")
			(net "SVID_ALERT_PVCCIO_CPU1")
		)
		(pad "2" smd rect
			(at 0 0.889 270)
			(size 0.508 0.508)
			(layers "F.Cu" "F.Mask" "F.Paste")
			(net "SVID_ALERT0_CPU1_R_N")
		)
		(zone
			(layer "F.Cu")
			(hatch none 0.5)
			(connect_pads
				(clearance 0)
			)
			(min_thickness 0.25)
			(keepout
				(tracks not_allowed)
				(vias allowed)
				(pads allowed)
				(copperpour not_allowed)
				(footprints allowed)
			)
			(placement
				(enabled no)
				(sheetname "")
			)
			(fill
				(thermal_gap 0.5)
				(thermal_bridge_width 0.5)
				(island_removal_mode 0)
			)
			(polygon
				(pts
					(xy 164.338 -67.564) (xy 164.338 -67.056) (xy 164.719 -67.056) (xy 164.719 -67.564)
				)
			)
		)
		(zone
			(layer "F.Cu")
			(hatch none 0.5)
			(connect_pads
				(clearance 0)
			)
			(min_thickness 0.25)
			(keepout
				(tracks allowed)
				(vias not_allowed)
				(pads allowed)
				(copperpour not_allowed)
				(footprints allowed)
			)
			(placement
				(enabled no)
				(sheetname "")
			)
			(fill
				(thermal_gap 0.5)
				(thermal_bridge_width 0.5)
				(island_removal_mode 0)
			)
			(polygon
				(pts
					(xy 164.719 -67.564) (xy 164.719 -67.056) (xy 164.338 -67.056) (xy 164.338 -67.564)
				)
			)
		)
	)
)
